#ISCELL
  pure_quanta quanta_title_block_c *
  *
#ISCELL
  pure_quanta_power cad_note *
  *
#CELL
  pure_quanta genoa_sp5 *
  page16_i167
#ISCELL
  mstr_standard offpage *
  page16_i168
#ISCELL
  mstr_standard offpage *
  page16_i169
#ISCELL
  mstr_standard tap *
  page16_i170
#ISCELL
  mstr_standard tap *
  page16_i171
#ISCELL
  mstr_standard tap *
  page16_i172
#ISCELL
  mstr_standard tap *
  page16_i173
#ISCELL
  mstr_standard tap *
  page16_i174
#ISCELL
  mstr_standard tap *
  page16_i175
#ISCELL
  mstr_standard tap *
  page16_i176
#ISCELL
  mstr_standard tap *
  page16_i177
#ISCELL
  mstr_standard tap *
  page16_i178
#ISCELL
  mstr_standard tap *
  page16_i179
#ISCELL
  mstr_standard tap *
  page16_i180
#ISCELL
  mstr_standard tap *
  page16_i181
#ISCELL
  mstr_standard tap *
  page16_i182
#ISCELL
  mstr_standard tap *
  page16_i183
#ISCELL
  mstr_standard tap *
  page16_i184
#ISCELL
  mstr_standard tap *
  page16_i185
#ISCELL
  mstr_standard tap *
  page16_i186
#ISCELL
  mstr_standard tap *
  page16_i187
#ISCELL
  mstr_standard tap *
  page16_i188
#ISCELL
  mstr_standard tap *
  page16_i189
#ISCELL
  mstr_standard tap *
  page16_i190
#ISCELL
  mstr_standard tap *
  page16_i191
#ISCELL
  mstr_standard tap *
  page16_i192
#ISCELL
  mstr_standard tap *
  page16_i193
#ISCELL
  mstr_standard tap *
  page16_i194
#ISCELL
  mstr_standard tap *
  page16_i195
#ISCELL
  mstr_standard tap *
  page16_i196
#ISCELL
  mstr_standard tap *
  page16_i197
#ISCELL
  mstr_standard tap *
  page16_i198
#ISCELL
  mstr_standard tap *
  page16_i199
#ISCELL
  mstr_standard tap *
  page16_i200
#ISCELL
  mstr_standard tap *
  page16_i201
#ISCELL
  mstr_standard tap *
  page16_i202
#ISCELL
  mstr_standard tap *
  page16_i203
#ISCELL
  mstr_standard tap *
  page16_i204
#ISCELL
  mstr_standard tap *
  page16_i205
#ISCELL
  mstr_standard offpage *
  page16_i206
#ISCELL
  mstr_standard tap *
  page16_i207
#ISCELL
  mstr_standard tap *
  page16_i208
#ISCELL
  mstr_standard tap *
  page16_i209
#ISCELL
  mstr_standard tap *
  page16_i210
#ISCELL
  mstr_standard tap *
  page16_i211
#ISCELL
  mstr_standard tap *
  page16_i212
#ISCELL
  mstr_standard tap *
  page16_i213
#ISCELL
  mstr_standard tap *
  page16_i214
#ISCELL
  mstr_standard tap *
  page16_i215
#ISCELL
  mstr_standard tap *
  page16_i216
#ISCELL
  mstr_standard tap *
  page16_i217
#ISCELL
  mstr_standard tap *
  page16_i218
#ISCELL
  mstr_standard tap *
  page16_i219
#ISCELL
  mstr_standard tap *
  page16_i220
#ISCELL
  mstr_standard tap *
  page16_i221
#ISCELL
  mstr_standard tap *
  page16_i222
#ISCELL
  mstr_standard tap *
  page16_i223
#ISCELL
  mstr_standard tap *
  page16_i224
#ISCELL
  mstr_standard tap *
  page16_i225
#ISCELL
  mstr_standard tap *
  page16_i226
#ISCELL
  mstr_standard tap *
  page16_i227
#ISCELL
  mstr_standard tap *
  page16_i228
#ISCELL
  mstr_standard tap *
  page16_i229
#ISCELL
  mstr_standard tap *
  page16_i230
#ISCELL
  mstr_standard tap *
  page16_i231
#ISCELL
  mstr_standard tap *
  page16_i232
#ISCELL
  mstr_standard tap *
  page16_i233
#ISCELL
  mstr_standard tap *
  page16_i234
#ISCELL
  mstr_standard tap *
  page16_i235
#ISCELL
  mstr_standard tap *
  page16_i236
#ISCELL
  mstr_standard tap *
  page16_i237
#ISCELL
  mstr_standard tap *
  page16_i238
#ISCELL
  mstr_standard tap *
  page16_i239
#ISCELL
  mstr_standard tap *
  page16_i240
#ISCELL
  mstr_standard tap *
  page16_i241
#ISCELL
  mstr_standard tap *
  page16_i242
#ISCELL
  mstr_standard offpage *
  page16_i243
#ISCELL
  mstr_standard tap *
  page16_i244
#ISCELL
  mstr_standard tap *
  page16_i245
#ISCELL
  mstr_standard tap *
  page16_i246
#ISCELL
  mstr_standard tap *
  page16_i247
#ISCELL
  mstr_standard tap *
  page16_i248
#ISCELL
  mstr_standard tap *
  page16_i249
#ISCELL
  mstr_standard tap *
  page16_i250
#ISCELL
  mstr_standard tap *
  page16_i251
#ISCELL
  mstr_standard tap *
  page16_i252
#ISCELL
  mstr_standard tap *
  page16_i253
#ISCELL
  mstr_standard tap *
  page16_i254
#ISCELL
  mstr_standard tap *
  page16_i255
#ISCELL
  mstr_standard tap *
  page16_i256
#ISCELL
  mstr_standard tap *
  page16_i257
#ISCELL
  mstr_standard tap *
  page16_i258
#ISCELL
  mstr_standard tap *
  page16_i259
#ISCELL
  mstr_standard tap *
  page16_i260
#ISCELL
  mstr_standard tap *
  page16_i261
#ISCELL
  mstr_standard tap *
  page16_i262
#ISCELL
  mstr_standard tap *
  page16_i263
#ISCELL
  mstr_standard tap *
  page16_i264
#ISCELL
  mstr_standard tap *
  page16_i265
#ISCELL
  mstr_standard tap *
  page16_i266
#ISCELL
  mstr_standard tap *
  page16_i267
#ISCELL
  mstr_standard tap *
  page16_i268
#ISCELL
  mstr_standard tap *
  page16_i269
#ISCELL
  mstr_standard tap *
  page16_i270
#ISCELL
  mstr_standard tap *
  page16_i271
#ISCELL
  mstr_standard tap *
  page16_i272
#ISCELL
  mstr_standard tap *
  page16_i273
#ISCELL
  mstr_standard tap *
  page16_i274
#ISCELL
  mstr_standard tap *
  page16_i275
#ISCELL
  mstr_standard tap *
  page16_i276
#ISCELL
  mstr_standard tap *
  page16_i277
#ISCELL
  mstr_standard tap *
  page16_i278
#ISCELL
  mstr_standard tap *
  page16_i279
#ISCELL
  mstr_standard tap *
  page16_i280
#ISCELL
  mstr_standard tap *
  page16_i281
#ISCELL
  mstr_standard tap *
  page16_i282
#ISCELL
  mstr_standard tap *
  page16_i283
#ISCELL
  mstr_standard tap *
  page16_i284
#ISCELL
  mstr_standard tap *
  page16_i285
#ISCELL
  mstr_standard tap *
  page16_i286
#ISCELL
  mstr_standard tap *
  page16_i287
#ISCELL
  mstr_standard tap *
  page16_i288
#ISCELL
  mstr_standard tap *
  page16_i289
#ISCELL
  mstr_standard tap *
  page16_i290
#ISCELL
  standard offpage *
  page16_i291
#ISCELL
  standard offpage *
  page16_i292
#ISCELL
  standard offpage *
  page16_i293
#ISCELL
  standard offpage *
  page16_i294
#ISCELL
  mstr_standard tap *
  page16_i295
#ISCELL
  mstr_standard tap *
  page16_i296
#ISCELL
  mstr_standard tap *
  page16_i297
#ISCELL
  mstr_standard tap *
  page16_i298
#ISCELL
  mstr_standard tap *
  page16_i299
#ISCELL
  mstr_standard tap *
  page16_i300
#ISCELL
  mstr_standard tap *
  page16_i301
#ISCELL
  mstr_standard tap *
  page16_i302
#ISCELL
  mstr_standard tap *
  page16_i303
#ISCELL
  mstr_standard tap *
  page16_i304
#ISCELL
  mstr_standard tap *
  page16_i305
#ISCELL
  mstr_standard tap *
  page16_i306
#ISCELL
  mstr_standard tap *
  page16_i307
#ISCELL
  mstr_standard tap *
  page16_i308
#ISCELL
  mstr_standard tap *
  page16_i309
#ISCELL
  standard offpage *
  page16_i310
#ISCELL
  standard offpage *
  page16_i311
#ISCELL
  standard offpage *
  page16_i312
#ISCELL
  standard offpage *
  page16_i313
#ISCELL
  standard offpage *
  page16_i314
#ISCELL
  standard offpage *
  page16_i315
#ISCELL
  mstr_standard offpage *
  page16_i316
#ISCELL
  standard offpage *
  page16_i317
#ISCELL
  standard offpage *
  page16_i318
#ISCELL
  standard offpage *
  page16_i319
#ISCELL
  standard offpage *
  page16_i320
#ISCELL
  standard offpage *
  page16_i321
#ISCELL
  standard offpage *
  page16_i322
#CELL
  pure_quanta q_res *
  page16_i323
#ISCELL
  mstr_standard offpage *
  page16_i324
